# T6G (Grand Teton) — schematic netlist excerpt (pin names and nets, part order shuffled) for the footprints in the layout excerpt that follows; sources: Cadence DE-HDL packaged netlist, KiCad conversion of 04192023_DAF0TMB3IC0_F0TG_MB_C_brd_V02_OCP.brd

C933  Q_CAP_DIFFBUS  DIFF BUS_0.22UF 6.3V 20% X6S  pkg C0201  page 63 : \1\ = P5E_CPU0_P0_TX_C_DP<0> ; \2\ = P5E_CPU0_P0_TX_DP<0>
R6244  Q_RES  10K 1% CHIP  pkg 0402LF  page 270 : A = P3V3_AUX ; B = PWRGD_P1V2_AUX
PC2156  Q_CAP  100NF 50V 10% X7R  pkg C0402  page 135 : A = P12V_OCP_IMON_1 ; B = GND

(kicad_pcb
	(version 20260206)
	(generator "pcbnew")
	(generator_version "10.0")
	(general
		(thickness 1.6)
		(legacy_teardrops no)
	)
	(paper "A4")
	(title_block
		(title "04192023_DAF0TMB3IC0_F0TG_MB_C_brd_V02_OCP.brd")
		(comment 1 "Grand Teton / footprints 2475-2477 of 8354")
	)
	(layers
		(0 "F.Cu" signal "TOP")
		(4 "In1.Cu" signal "GND")
		(6 "In2.Cu" signal "IN1")
		(8 "In3.Cu" signal "GND1")
		(10 "In4.Cu" signal "IN2")
		(12 "In5.Cu" signal "GND2")
		(14 "In6.Cu" signal "IN3")
		(16 "In7.Cu" signal "GND3")
		(18 "In8.Cu" signal "VCC")
		(20 "In9.Cu" signal "VCC1")
		(22 "In10.Cu" signal "GND4")
		(24 "In11.Cu" signal "IN4")
		(26 "In12.Cu" signal "GND5")
		(28 "In13.Cu" signal "IN5")
		(30 "In14.Cu" signal "GND6")
		(32 "In15.Cu" signal "IN6")
		(34 "In16.Cu" signal "GND7")
		(2 "B.Cu" signal "BOTTOM")
		(9 "F.Adhes" user "F.Adhesive")
		(11 "B.Adhes" user "B.Adhesive")
		(13 "F.Paste" user "Package Geometry/Pastemask Top")
		(15 "B.Paste" user "Package Geometry/Pastemask Bottom")
		(5 "F.SilkS" user "Ref Des/Silkscreen Top")
		(7 "B.SilkS" user "Ref Des/Silkscreen Bottom")
		(1 "F.Mask" user "Board Geometry/Soldermask Top")
		(3 "B.Mask" user "Board Geometry/Soldermask Bottom")
		(17 "Dwgs.User" user "User.Drawings")
		(19 "Cmts.User" user "User.Comments")
		(21 "Eco1.User" user "User.Eco1")
		(23 "Eco2.User" user "User.Eco2")
		(25 "Edge.Cuts" user "Board Geometry/Outline")
		(27 "Margin" user)
		(31 "F.CrtYd" user "Package Geometry/Place Bound Top")
		(29 "B.CrtYd" user "Package Geometry/Place Bound Bottom")
		(35 "F.Fab" user "Ref Des/Assembly Top")
		(33 "B.Fab" user "Ref Des/Assembly Bottom")
	)
	(footprint ""
		(layer "F.Cu")
		(at 123.725178 -72.829166 90)
		(property "Reference" "R6244"
			(at 0 0 90)
			(layer "F.SilkS")
			(hide yes)
			(effects
				(font
					(size 1.27 1.27)
				)
			)
		)
		(property "Value" ""
			(at 0 0 90)
			(layer "F.Fab")
			(effects
				(font
					(size 1.27 1.27)
				)
			)
		)
		(duplicate_pad_numbers_are_jumpers no)
		(fp_line
			(start 0.7874 -0.4064)
			(end 0.7874 0.4064)
			(stroke
				(width 0.1524)
				(type default)
			)
			(layer "F.SilkS")
		)
		(fp_line
			(start -0.7874 -0.4064)
			(end 0.7874 -0.4064)
			(stroke
				(width 0.1524)
				(type default)
			)
			(layer "F.SilkS")
		)
		(fp_line
			(start 0.7874 0.4064)
			(end -0.7874 0.4064)
			(stroke
				(width 0.1524)
				(type default)
			)
			(layer "F.SilkS")
		)
		(fp_line
			(start -0.7874 0.4064)
			(end -0.7874 -0.4064)
			(stroke
				(width 0.1524)
				(type default)
			)
			(layer "F.SilkS")
		)
		(fp_line
			(start -0.12065 -0.305054)
			(end -0.12065 -0.2794)
			(stroke
				(width 0.1)
				(type default)
			)
			(layer "F.Fab")
		)
		(fp_line
			(start -0.67945 -0.305054)
			(end -0.12065 -0.305054)
			(stroke
				(width 0.1)
				(type default)
			)
			(layer "F.Fab")
		)
		(fp_line
			(start 0.67945 -0.3048)
			(end 0.67945 0.3048)
			(stroke
				(width 0.1)
				(type default)
			)
			(layer "F.Fab")
		)
		(fp_line
			(start 0.12065 -0.3048)
			(end 0.67945 -0.3048)
			(stroke
				(width 0.1)
				(type default)
			)
			(layer "F.Fab")
		)
		(fp_line
			(start 0.12065 -0.2794)
			(end 0.12065 -0.3048)
			(stroke
				(width 0.1)
				(type default)
			)
			(layer "F.Fab")
		)
		(fp_line
			(start -0.12065 -0.2794)
			(end 0.12065 -0.2794)
			(stroke
				(width 0.1)
				(type default)
			)
			(layer "F.Fab")
		)
		(fp_line
			(start 0.120396 0.2794)
			(end -0.12065 0.2794)
			(stroke
				(width 0.1)
				(type default)
			)
			(layer "F.Fab")
		)
		(fp_line
			(start -0.12065 0.2794)
			(end -0.12065 0.3048)
			(stroke
				(width 0.1)
				(type default)
			)
			(layer "F.Fab")
		)
		(fp_line
			(start 0.67945 0.3048)
			(end 0.120396 0.3048)
			(stroke
				(width 0.1)
				(type default)
			)
			(layer "F.Fab")
		)
		(fp_line
			(start 0.120396 0.3048)
			(end 0.120396 0.2794)
			(stroke
				(width 0.1)
				(type default)
			)
			(layer "F.Fab")
		)
		(fp_line
			(start -0.12065 0.3048)
			(end -0.67945 0.3048)
			(stroke
				(width 0.1)
				(type default)
			)
			(layer "F.Fab")
		)
		(fp_line
			(start -0.67945 0.3048)
			(end -0.67945 -0.305054)
			(stroke
				(width 0.1)
				(type default)
			)
			(layer "F.Fab")
		)
		(pad "1" smd circle
			(at -0.40005 0 90)
			(size 0 0)
			(layers "F.Cu" "F.Mask" "F.Paste")
			(net "P3V3_AUX")
		)
		(pad "2" smd circle
			(at 0.40005 0 90)
			(size 0 0)
			(layers "F.Cu" "F.Mask" "F.Paste")
			(net "PWRGD_P1V2_AUX")
		)
	)
	(footprint ""
		(layer "F.Cu")
		(at 439.272172 -32.173418 90)
		(property "Reference" "PC2156"
			(at 0 0 90)
			(layer "F.SilkS")
			(hide yes)
			(effects
				(font
					(size 1.27 1.27)
				)
			)
		)
		(property "Value" ""
			(at 0 0 90)
			(layer "F.Fab")
			(effects
				(font
					(size 1.27 1.27)
				)
			)
		)
		(duplicate_pad_numbers_are_jumpers no)
		(fp_line
			(start 0.7874 -0.4064)
			(end 0.7874 0.4064)
			(stroke
				(width 0.1524)
				(type default)
			)
			(layer "F.SilkS")
		)
		(fp_line
			(start -0.7874 -0.4064)
			(end 0.7874 -0.4064)
			(stroke
				(width 0.1524)
				(type default)
			)
			(layer "F.SilkS")
		)
		(fp_line
			(start 0.7874 0.4064)
			(end -0.7874 0.4064)
			(stroke
				(width 0.1524)
				(type default)
			)
			(layer "F.SilkS")
		)
		(fp_line
			(start -0.7874 0.4064)
			(end -0.7874 -0.4064)
			(stroke
				(width 0.1524)
				(type default)
			)
			(layer "F.SilkS")
		)
		(fp_line
			(start -0.12065 -0.305054)
			(end -0.12065 -0.2794)
			(stroke
				(width 0.1)
				(type default)
			)
			(layer "F.Fab")
		)
		(fp_line
			(start -0.67945 -0.305054)
			(end -0.12065 -0.305054)
			(stroke
				(width 0.1)
				(type default)
			)
			(layer "F.Fab")
		)
		(fp_line
			(start 0.67945 -0.3048)
			(end 0.67945 0.3048)
			(stroke
				(width 0.1)
				(type default)
			)
			(layer "F.Fab")
		)
		(fp_line
			(start 0.12065 -0.3048)
			(end 0.67945 -0.3048)
			(stroke
				(width 0.1)
				(type default)
			)
			(layer "F.Fab")
		)
		(fp_line
			(start 0.12065 -0.2794)
			(end 0.12065 -0.3048)
			(stroke
				(width 0.1)
				(type default)
			)
			(layer "F.Fab")
		)
		(fp_line
			(start -0.12065 -0.2794)
			(end 0.12065 -0.2794)
			(stroke
				(width 0.1)
				(type default)
			)
			(layer "F.Fab")
		)
		(fp_line
			(start 0.120396 0.2794)
			(end -0.12065 0.2794)
			(stroke
				(width 0.1)
				(type default)
			)
			(layer "F.Fab")
		)
		(fp_line
			(start -0.12065 0.2794)
			(end -0.12065 0.3048)
			(stroke
				(width 0.1)
				(type default)
			)
			(layer "F.Fab")
		)
		(fp_line
			(start 0.67945 0.3048)
			(end 0.120396 0.3048)
			(stroke
				(width 0.1)
				(type default)
			)
			(layer "F.Fab")
		)
		(fp_line
			(start 0.120396 0.3048)
			(end 0.120396 0.2794)
			(stroke
				(width 0.1)
				(type default)
			)
			(layer "F.Fab")
		)
		(fp_line
			(start -0.12065 0.3048)
			(end -0.67945 0.3048)
			(stroke
				(width 0.1)
				(type default)
			)
			(layer "F.Fab")
		)
		(fp_line
			(start -0.67945 0.3048)
			(end -0.67945 -0.305054)
			(stroke
				(width 0.1)
				(type default)
			)
			(layer "F.Fab")
		)
		(pad "1" smd circle
			(at -0.40005 0 90)
			(size 0 0)
			(layers "F.Cu" "F.Mask" "F.Paste")
			(net "P12V_OCP_IMON_1")
		)
		(pad "2" smd circle
			(at 0.40005 0 90)
			(size 0 0)
			(layers "F.Cu" "F.Mask" "F.Paste")
			(net "GND")
		)
	)
	(footprint ""
		(layer "F.Cu")
		(at 298.967144 -390.77646 180)
		(property "Reference" "C933"
			(at 0 0 180)
			(layer "F.SilkS")
			(hide yes)
			(effects
				(font
					(size 1.27 1.27)
				)
			)
		)
		(property "Value" ""
			(at 0 0 180)
			(layer "F.Fab")
			(effects
				(font
					(size 1.27 1.27)
				)
			)
		)
		(duplicate_pad_numbers_are_jumpers no)
		(fp_line
			(start 0.299974 0.150114)
			(end -0.299974 0.150114)
			(stroke
				(width 0.1)
				(type default)
			)
			(layer "F.Fab")
		)
		(fp_line
			(start 0.299974 -0.150114)
			(end 0.299974 0.150114)
			(stroke
				(width 0.1)
				(type default)
			)
			(layer "F.Fab")
		)
		(fp_line
			(start -0.299974 0.150114)
			(end -0.299974 -0.150114)
			(stroke
				(width 0.1)
				(type default)
			)
			(layer "F.Fab")
		)
		(fp_line
			(start -0.299974 -0.150114)
			(end 0.299974 -0.150114)
			(stroke
				(width 0.1)
				(type default)
			)
			(layer "F.Fab")
		)
		(pad "1" smd rect
			(at -0.2667 0 180)
			(size 0.3048 0.381)
			(layers "F.Cu" "F.Mask" "F.Paste")
			(net "P5E_CPU0_P0_TX_C_DP<0>")
		)
		(pad "2" smd rect
			(at 0.2667 0 180)
			(size 0.3048 0.381)
			(layers "F.Cu" "F.Mask" "F.Paste")
			(net "P5E_CPU0_P0_TX_DP<0>")
		)
	)
)
